FILE_TYPE = CONNECTIVITY;
{Allegro Design Entry HDL 17.2-2016 S081 (4005846) 1/11/2022}
"PAGE_NUMBER" = 48;
0"NC";
1"M_L_CPU1_SA_DQ<31:0>";
2"M_L_CPU1_SB_DQ<31:0>";
3"M_L_CPU1_SA_CB<7:0>";
4"M_L_CPU1_SB_CB<7:0>";
5"M_L_CPU1_SA_DQS_DP<9:0>";
6"M_L_CPU1_SB_DQS_DP<9:0>";
7"M_L_CPU1_SA_CA<6:0>";
8"M_L_CPU1_SB_CA<6:0>";
9"M_L_CPU1_SA_DQS_DN<9:0>";
10"M_L_CPU1_SB_DQS_DN<9:0>";
11"M_L_CPU1_ALERT_N";
12"TP_M_L_CPU1_SA_TEST39L";
13"M_L_CPU1_ALERT_R_N";
14"M_L_CPU1_CLK_DP<0>";
15"M_L_CPU1_CLK_DN<0>";
16"M_L_CPU1_SA_CS_N<0>";
17"M_L_CPU1_SA_CS_N<1>";
18"M_L_CPU1_SA_RSP<0>";
19"M_L_CPU1_SA_PAR";
20"M_L_CPU1_SB_CS_N<1>";
21"M_L_CPU1_SB_CS_N<0>";
22"M_L_CPU1_SB_PAR";
23"M_L_CPU1_SB_RSP<0>";
24"M_L_CPU1_RESET_N";
25"M_L_CPU1_SA_CA<1>";
26"M_L_CPU1_SB_CA<0>";
27"M_L_CPU1_SB_DQS_DN<8>";
28"M_L_CPU1_SA_CA<0>";
29"M_L_CPU1_SB_CA<6>";
30"M_L_CPU1_SA_CA<6>";
31"M_L_CPU1_SB_CA<5>";
32"M_L_CPU1_SB_DQS_DP<9>";
33"M_L_CPU1_SA_CA<5>";
34"M_L_CPU1_SB_CA<4>";
35"M_L_CPU1_SB_DQS_DP<8>";
36"M_L_CPU1_SA_CA<4>";
37"M_L_CPU1_SB_CA<3>";
38"M_L_CPU1_SA_CA<3>";
39"M_L_CPU1_SB_CA<2>";
40"M_L_CPU1_SA_CA<2>";
41"M_L_CPU1_SB_CA<1>";
42"M_L_CPU1_SB_DQS_DN<9>";
43"M_L_CPU1_SB_DQS_DP<4>";
44"M_L_CPU1_SA_DQS_DP<9>";
45"M_L_CPU1_SB_DQS_DP<3>";
46"M_L_CPU1_SB_DQS_DN<7>";
47"M_L_CPU1_SB_DQS_DP<2>";
48"M_L_CPU1_SB_DQS_DN<6>";
49"M_L_CPU1_SB_DQS_DP<1>";
50"M_L_CPU1_SB_DQS_DN<5>";
51"M_L_CPU1_SB_DQS_DP<0>";
52"M_L_CPU1_SB_DQS_DN<4>";
53"M_L_CPU1_SA_DQS_DN<9>";
54"M_L_CPU1_SB_DQS_DN<3>";
55"M_L_CPU1_SA_DQS_DN<8>";
56"M_L_CPU1_SB_DQS_DN<2>";
57"M_L_CPU1_SB_DQS_DN<1>";
58"M_L_CPU1_SB_DQS_DN<0>";
59"M_L_CPU1_SB_DQS_DP<7>";
60"M_L_CPU1_SB_DQS_DP<6>";
61"M_L_CPU1_SB_DQS_DP<5>";
62"M_L_CPU1_SA_DQS_DP<8>";
63"M_L_CPU1_SA_DQS_DP<7>";
64"M_L_CPU1_SA_DQS_DP<6>";
65"M_L_CPU1_SA_DQS_DP<5>";
66"M_L_CPU1_SA_DQS_DP<4>";
67"M_L_CPU1_SA_DQS_DP<3>";
68"M_L_CPU1_SA_DQS_DN<7>";
69"M_L_CPU1_SA_DQS_DP<2>";
70"M_L_CPU1_SA_DQS_DN<6>";
71"M_L_CPU1_SA_DQS_DP<1>";
72"M_L_CPU1_SA_DQS_DN<5>";
73"M_L_CPU1_SA_DQS_DP<0>";
74"M_L_CPU1_SA_DQS_DN<4>";
75"M_L_CPU1_SA_DQS_DN<3>";
76"M_L_CPU1_SA_DQS_DN<2>";
77"M_L_CPU1_SA_DQS_DN<1>";
78"M_L_CPU1_SA_DQS_DN<0>";
79"M_L_CPU1_SB_CB<7>";
80"M_L_CPU1_SB_CB<6>";
81"M_L_CPU1_SB_CB<5>";
82"M_L_CPU1_SB_CB<4>";
83"M_L_CPU1_SB_CB<3>";
84"M_L_CPU1_SB_CB<2>";
85"M_L_CPU1_SA_CB<7>";
86"M_L_CPU1_SB_CB<1>";
87"M_L_CPU1_SA_CB<6>";
88"M_L_CPU1_SB_CB<0>";
89"M_L_CPU1_SA_CB<1>";
90"M_L_CPU1_SA_CB<0>";
91"M_L_CPU1_SB_DQ<29>";
92"M_L_CPU1_SB_DQ<28>";
93"M_L_CPU1_SB_DQ<27>";
94"M_L_CPU1_SB_DQ<26>";
95"M_L_CPU1_SB_DQ<25>";
96"M_L_CPU1_SB_DQ<24>";
97"M_L_CPU1_SB_DQ<23>";
98"M_L_CPU1_SB_DQ<22>";
99"M_L_CPU1_SB_DQ<21>";
100"M_L_CPU1_SB_DQ<20>";
101"M_L_CPU1_SB_DQ<31>";
102"M_L_CPU1_SA_CB<5>";
103"M_L_CPU1_SB_DQ<30>";
104"M_L_CPU1_SA_CB<4>";
105"M_L_CPU1_SA_CB<3>";
106"M_L_CPU1_SA_CB<2>";
107"M_L_CPU1_SB_DQ<3>";
108"M_L_CPU1_SB_DQ<2>";
109"M_L_CPU1_SB_DQ<1>";
110"M_L_CPU1_SB_DQ<19>";
111"M_L_CPU1_SB_DQ<18>";
112"M_L_CPU1_SB_DQ<17>";
113"M_L_CPU1_SB_DQ<16>";
114"M_L_CPU1_SB_DQ<15>";
115"M_L_CPU1_SB_DQ<14>";
116"M_L_CPU1_SB_DQ<13>";
117"M_L_CPU1_SB_DQ<12>";
118"M_L_CPU1_SB_DQ<11>";
119"M_L_CPU1_SB_DQ<9>";
120"M_L_CPU1_SB_DQ<10>";
121"M_L_CPU1_SB_DQ<8>";
122"M_L_CPU1_SB_DQ<7>";
123"M_L_CPU1_SB_DQ<6>";
124"M_L_CPU1_SB_DQ<5>";
125"M_L_CPU1_SB_DQ<4>";
126"M_L_CPU1_SA_DQ<21>";
127"M_L_CPU1_SA_DQ<20>";
128"M_L_CPU1_SA_DQ<31>";
129"M_L_CPU1_SA_DQ<30>";
130"M_L_CPU1_SB_DQ<0>";
131"M_L_CPU1_SA_DQ<19>";
132"M_L_CPU1_SA_DQ<18>";
133"M_L_CPU1_SA_DQ<29>";
134"M_L_CPU1_SA_DQ<17>";
135"M_L_CPU1_SA_DQ<28>";
136"M_L_CPU1_SA_DQ<16>";
137"M_L_CPU1_SA_DQ<27>";
138"M_L_CPU1_SA_DQ<26>";
139"M_L_CPU1_SA_DQ<25>";
140"M_L_CPU1_SA_DQ<24>";
141"M_L_CPU1_SA_DQ<23>";
142"M_L_CPU1_SA_DQ<22>";
143"M_L_CPU1_SA_DQ<4>";
144"M_L_CPU1_SA_DQ<10>";
145"M_L_CPU1_SA_DQ<3>";
146"M_L_CPU1_SA_DQ<2>";
147"M_L_CPU1_SA_DQ<1>";
148"M_L_CPU1_SA_DQ<0>";
149"M_L_CPU1_SA_DQ<9>";
150"M_L_CPU1_SA_DQ<15>";
151"M_L_CPU1_SA_DQ<8>";
152"M_L_CPU1_SA_DQ<14>";
153"M_L_CPU1_SA_DQ<7>";
154"M_L_CPU1_SA_DQ<13>";
155"M_L_CPU1_SA_DQ<6>";
156"M_L_CPU1_SA_DQ<12>";
157"M_L_CPU1_SA_DQ<5>";
158"M_L_CPU1_SA_DQ<11>";
%"GENOA_SP5"
"35","(-4550,3550)","0","pure_quanta","I159";
;
LOCATION"U26"
$SEC"35"
CDS_SEC"35"
PART_TYPE"SMLF"
MATERIAL"IO"
VALUE"SOCKET6096_13568-001"
PART_NUMBER"DGA^6000030"
CDS_LIB"pure_quanta"
CDS_LMAN_SYM_OUTLINE"-650,2525,650,-2525"
NEEDS_NO_SIZE"TRUE";
"TEST39L"
$PN"BF11"12;
"MLA_CA1"
$PN"AY9"25;
"MLA_CHECK1"
$PN"AK11"89;
"MLA_DATA4"
$PN"J9"143;
"MLA_DATA10"
$PN"M9"144;
"MLA_DATA21"
$PN"AB11"126;
"MLB_CA0"
$PN"BG10"26;
"MLB_DATA3"
$PN"CD11"107;
"MLB_DQS_H4"
$PN"BY11"43;
"MLB_DQS_L8"
$PN"DC10"27;
"MLA_CA0"
$PN"AW9"28;
"MLA_CHECK0"
$PN"AJ9"90;
"MLA_DATA3"
$PN"G10"145;
"MLA_DATA20"
$PN"AA9"127;
"MLA_DATA31"
$PN"AJ10"128;
"MLA_DQS_H9"
$PN"AN10"44;
"MLB_DATA2"
$PN"CC9"108;
"MLB_DQS_H3"
$PN"DB9"45;
"MLB_DQS_L7"
$PN"CU10"46;
"MLA1_CS_L1"
$PN"AW10"0;
"MLA_DATA2"
$PN"F9"146;
"MLA_DATA30"
$PN"AH9"129;
"MLA_DQS_H8"
$PN"AG10"62;
"MLB_DATA1"
$PN"CC10"109;
"MLB_DATA19"
$PN"CT11"110;
"MLB_DQS_H2"
$PN"CT9"47;
"MLB_DQS_L6"
$PN"CL10"48;
"MLA0_CS_L1"
$PN"AV11"17;
"MLA1_CS_L0"
$PN"AV9"0;
"MLA_DATA1"
$PN"F11"147;
"MLA_DQS_H7"
$PN"AA10"63;
"MLB_DATA0"
$PN"CB9"130;
"MLB_DATA18"
$PN"CR9"111;
"MLB_DATA29"
$PN"DE10"91;
"MLB_DQS_H1"
$PN"CK9"49;
"MLB_DQS_L5"
$PN"CE10"50;
"ML1_CLK_L"
$PN"BG9"0;
"MLA0_CS_L0"
$PN"AU9"16;
"MLA_DATA0"
$PN"E9"148;
"MLA_DQS_H6"
$PN"R10"64;
"MLB_DATA17"
$PN"CR10"112;
"MLB_DATA28"
$PN"DD9"92;
"MLB_DQS_H0"
$PN"CD9"51;
"MLB_DQS_L4"
$PN"BW10"52;
"MLB_PAR"
$PN"BL10"22;
"ML0_CLK_L"
$PN"BD9"15;
"MLA_DQS_H5"
$PN"J10"65;
"MLA_DQS_L9"
$PN"AM11"53;
"MLA_PAR"
$PN"BC10"19;
"MLB1_RSP_L"
$PN"BR9"0;
"MLB_CHECK7"
$PN"BV11"79;
"MLB_DATA16"
$PN"CP9"113;
"MLB_DATA27"
$PN"DB11"93;
"MLB_DQS_L3"
$PN"DC9"54;
"MLA_DQS_H4"
$PN"AL9"66;
"MLA_DQS_L8"
$PN"AF11"55;
"MLB0_RSP_L"
$PN"BP9"23;
"MLB_CHECK6"
$PN"BU9"80;
"MLB_DATA15"
$PN"CP11"114;
"MLB_DATA26"
$PN"DA9"94;
"MLB_DQS_L2"
$PN"CU9"56;
"MLA_DQS_H3"
$PN"AE9"67;
"MLA_DQS_L7"
$PN"Y11"68;
"MLB_CHECK5"
$PN"BU10"81;
"MLB_DATA14"
$PN"CN9"115;
"MLB_DATA25"
$PN"DA10"95;
"MLB_DQS_L1"
$PN"CL9"57;
"ML1_CLK_H"
$PN"BF9"0;
"MLA_DATA19"
$PN"W10"131;
"MLA_DQS_H2"
$PN"W9"69;
"MLA_DQS_L6"
$PN"P11"70;
"MLB_CHECK4"
$PN"BT9"82;
"MLB_DATA13"
$PN"CN10"116;
"MLB_DATA24"
$PN"CY9"96;
"MLB_DQS_L0"
$PN"CE9"58;
"ML0_CLK_H"
$PN"BC9"14;
"MLA_DATA18"
$PN"V9"132;
"MLA_DATA29"
$PN"AH11"133;
"MLA_DQS_H1"
$PN"N9"71;
"MLA_DQS_L5"
$PN"H11"72;
"MLB_CHECK3"
$PN"CB11"83;
"MLB_DATA12"
$PN"CM9"117;
"MLB_DATA23"
$PN"CY11"97;
"MLA_DATA17"
$PN"V11"134;
"MLA_DATA28"
$PN"AG9"135;
"MLA_DQS_H0"
$PN"G9"73;
"MLA_DQS_L4"
$PN"AM9"74;
"MLB_CHECK2"
$PN"CA9"84;
"MLB_DATA11"
$PN"CK11"118;
"MLB_DATA22"
$PN"CW9"98;
"ML_ALERT_L"
$PN"AT11"13;
"MLA1_RSP_L"
$PN"BP11"0;
"MLA_CHECK7"
$PN"AR10"85;
"MLA_DATA16"
$PN"U9"136;
"MLA_DATA27"
$PN"AE10"137;
"MLA_DQS_L3"
$PN"AF9"75;
"MLB_CA6"
$PN"BK9"29;
"MLB_CHECK1"
$PN"CA10"86;
"MLB_DATA9"
$PN"CJ10"119;
"MLB_DATA10"
$PN"CJ9"120;
"MLB_DATA21"
$PN"CW10"99;
"MLA0_RSP_L"
$PN"BN10"18;
"MLA_CA6"
$PN"BB11"30;
"MLA_CHECK6"
$PN"AP9"87;
"MLA_DATA9"
$PN"M11"149;
"MLA_DATA15"
$PN"U10"150;
"MLA_DATA26"
$PN"AD9"138;
"MLA_DQS_L2"
$PN"Y9"76;
"MLB_CA5"
$PN"BK11"31;
"MLB_CHECK0"
$PN"BY9"88;
"MLB_DATA8"
$PN"CH9"121;
"MLB_DATA20"
$PN"CV9"100;
"MLB_DATA31"
$PN"DF9"101;
"MLB_DQS_H9"
$PN"BV9"32;
"MLA_CA5"
$PN"BB9"33;
"MLA_CHECK5"
$PN"AP11"102;
"MLA_DATA8"
$PN"L9"151;
"MLA_DATA14"
$PN"T9"152;
"MLA_DATA25"
$PN"AD11"139;
"MLA_DQS_L1"
$PN"P9"77;
"MLB1_CS_L1"
$PN"BM9"0;
"MLB_CA4"
$PN"BJ10"34;
"MLB_DATA7"
$PN"CH11"122;
"MLB_DATA30"
$PN"DE9"103;
"MLB_DQS_H8"
$PN"DD11"35;
"MLA_CA4"
$PN"BA9"36;
"MLA_CHECK4"
$PN"AN9"104;
"MLA_DATA7"
$PN"L10"153;
"MLA_DATA13"
$PN"T11"154;
"MLA_DATA24"
$PN"AC9"140;
"MLA_DQS_L0"
$PN"H9"78;
"MLB0_CS_L1"
$PN"BN9"20;
"MLB1_CS_L0"
$PN"BL9"0;
"MLB_CA3"
$PN"BJ9"37;
"MLB_DATA6"
$PN"CG9"123;
"MLB_DQS_H7"
$PN"CV11"59;
"MLA_CA3"
$PN"BA10"38;
"MLA_CHECK3"
$PN"AL10"105;
"MLA_DATA6"
$PN"K9"155;
"MLA_DATA12"
$PN"R9"156;
"MLA_DATA23"
$PN"AC10"141;
"MLB0_CS_L0"
$PN"BM11"21;
"MLB_CA2"
$PN"BH9"39;
"MLB_DATA5"
$PN"CG10"124;
"MLB_DQS_H6"
$PN"CM11"60;
"ML_RESET_L"
$PN"AU10"24;
"MLA_CA2"
$PN"AY11"40;
"MLA_CHECK2"
$PN"AK9"106;
"MLA_DATA5"
$PN"K11"157;
"MLA_DATA11"
$PN"N10"158;
"MLA_DATA22"
$PN"AB9"142;
"MLB_CA1"
$PN"BH11"41;
"MLB_DATA4"
$PN"CF9"125;
"MLB_DQS_H5"
$PN"CF11"61;
"MLB_DQS_L9"
$PN"BW9"42;
%"TAP"
"1","(-3275,5925)","0","mstr_standard","I162";
;
CDS_LIB"mstr_standard"
BODY_TYPE"PLUMBING"
HDL_TAP"TRUE";
"B \NAC \NWC"1;
"S \NAC"
BN"0"148;
%"TAP"
"1","(-3275,5775)","0","mstr_standard","I163";
;
CDS_LIB"mstr_standard"
BODY_TYPE"PLUMBING"
HDL_TAP"TRUE";
"B \NAC \NWC"1;
"S \NAC"
BN"3"145;
%"TAP"
"1","(-3275,5825)","0","mstr_standard","I164";
;
CDS_LIB"mstr_standard"
BODY_TYPE"PLUMBING"
HDL_TAP"TRUE";
"B \NAC \NWC"1;
"S \NAC"
BN"2"146;
%"TAP"
"1","(-3275,5875)","0","mstr_standard","I165";
;
CDS_LIB"mstr_standard"
BODY_TYPE"PLUMBING"
HDL_TAP"TRUE";
"B \NAC \NWC"1;
"S \NAC"
BN"1"147;
%"TAP"
"1","(-3275,5725)","0","mstr_standard","I166";
;
CDS_LIB"mstr_standard"
BODY_TYPE"PLUMBING"
HDL_TAP"TRUE";
"B \NAC \NWC"1;
"S \NAC"
BN"4"143;
%"TAP"
"1","(-3275,5675)","0","mstr_standard","I167";
;
CDS_LIB"mstr_standard"
BODY_TYPE"PLUMBING"
HDL_TAP"TRUE";
"B \NAC \NWC"1;
"S \NAC"
BN"5"157;
%"TAP"
"1","(-3275,5575)","0","mstr_standard","I168";
;
CDS_LIB"mstr_standard"
BODY_TYPE"PLUMBING"
HDL_TAP"TRUE";
"B \NAC \NWC"1;
"S \NAC"
BN"7"153;
%"TAP"
"1","(-3275,5625)","0","mstr_standard","I169";
;
CDS_LIB"mstr_standard"
BODY_TYPE"PLUMBING"
HDL_TAP"TRUE";
"B \NAC \NWC"1;
"S \NAC"
BN"6"155;
%"TAP"
"1","(-3275,5425)","0","mstr_standard","I170";
;
CDS_LIB"mstr_standard"
BODY_TYPE"PLUMBING"
HDL_TAP"TRUE";
"B \NAC \NWC"1;
"S \NAC"
BN"9"149;
%"TAP"
"1","(-3275,5475)","0","mstr_standard","I171";
;
CDS_LIB"mstr_standard"
BODY_TYPE"PLUMBING"
HDL_TAP"TRUE";
"B \NAC \NWC"1;
"S \NAC"
BN"8"151;
%"TAP"
"1","(-3275,5375)","0","mstr_standard","I172";
;
CDS_LIB"mstr_standard"
BODY_TYPE"PLUMBING"
HDL_TAP"TRUE";
"B \NAC \NWC"1;
"S \NAC"
BN"10"144;
%"TAP"
"1","(-3275,5325)","0","mstr_standard","I173";
;
CDS_LIB"mstr_standard"
BODY_TYPE"PLUMBING"
HDL_TAP"TRUE";
"B \NAC \NWC"1;
"S \NAC"
BN"11"158;
%"TAP"
"1","(-3275,5275)","0","mstr_standard","I174";
;
CDS_LIB"mstr_standard"
BODY_TYPE"PLUMBING"
HDL_TAP"TRUE";
"B \NAC \NWC"1;
"S \NAC"
BN"12"156;
%"TAP"
"1","(-3275,5225)","0","mstr_standard","I175";
;
CDS_LIB"mstr_standard"
BODY_TYPE"PLUMBING"
HDL_TAP"TRUE";
"B \NAC \NWC"1;
"S \NAC"
BN"13"154;
%"TAP"
"1","(-3275,5125)","0","mstr_standard","I176";
;
CDS_LIB"mstr_standard"
BODY_TYPE"PLUMBING"
HDL_TAP"TRUE";
"B \NAC \NWC"1;
"S \NAC"
BN"15"150;
%"TAP"
"1","(-3275,5175)","0","mstr_standard","I177";
;
CDS_LIB"mstr_standard"
BODY_TYPE"PLUMBING"
HDL_TAP"TRUE";
"B \NAC \NWC"1;
"S \NAC"
BN"14"152;
%"TAP"
"1","(-3275,5025)","0","mstr_standard","I178";
;
CDS_LIB"mstr_standard"
BODY_TYPE"PLUMBING"
HDL_TAP"TRUE";
"B \NAC \NWC"1;
"S \NAC"
BN"16"136;
%"TAP"
"1","(-3275,4875)","0","mstr_standard","I179";
;
CDS_LIB"mstr_standard"
BODY_TYPE"PLUMBING"
HDL_TAP"TRUE";
"B \NAC \NWC"1;
"S \NAC"
BN"19"131;
%"TAP"
"1","(-3275,4925)","0","mstr_standard","I180";
;
CDS_LIB"mstr_standard"
BODY_TYPE"PLUMBING"
HDL_TAP"TRUE";
"B \NAC \NWC"1;
"S \NAC"
BN"18"132;
%"TAP"
"1","(-3275,4975)","0","mstr_standard","I181";
;
CDS_LIB"mstr_standard"
BODY_TYPE"PLUMBING"
HDL_TAP"TRUE";
"B \NAC \NWC"1;
"S \NAC"
BN"17"134;
%"TAP"
"1","(-3275,4825)","0","mstr_standard","I182";
;
CDS_LIB"mstr_standard"
BODY_TYPE"PLUMBING"
HDL_TAP"TRUE";
"B \NAC \NWC"1;
"S \NAC"
BN"20"127;
%"TAP"
"1","(-3275,4775)","0","mstr_standard","I183";
;
CDS_LIB"mstr_standard"
BODY_TYPE"PLUMBING"
HDL_TAP"TRUE";
"B \NAC \NWC"1;
"S \NAC"
BN"21"126;
%"TAP"
"1","(-3275,4675)","0","mstr_standard","I184";
;
CDS_LIB"mstr_standard"
BODY_TYPE"PLUMBING"
HDL_TAP"TRUE";
"B \NAC \NWC"1;
"S \NAC"
BN"23"141;
%"TAP"
"1","(-3275,4725)","0","mstr_standard","I185";
;
CDS_LIB"mstr_standard"
BODY_TYPE"PLUMBING"
HDL_TAP"TRUE";
"B \NAC \NWC"1;
"S \NAC"
BN"22"142;
%"TAP"
"1","(-3275,4525)","0","mstr_standard","I186";
;
CDS_LIB"mstr_standard"
BODY_TYPE"PLUMBING"
HDL_TAP"TRUE";
"B \NAC \NWC"1;
"S \NAC"
BN"25"139;
%"TAP"
"1","(-3275,4575)","0","mstr_standard","I187";
;
CDS_LIB"mstr_standard"
BODY_TYPE"PLUMBING"
HDL_TAP"TRUE";
"B \NAC \NWC"1;
"S \NAC"
BN"24"140;
%"TAP"
"1","(-3275,4375)","0","mstr_standard","I188";
;
CDS_LIB"mstr_standard"
BODY_TYPE"PLUMBING"
HDL_TAP"TRUE";
"B \NAC \NWC"1;
"S \NAC"
BN"28"135;
%"TAP"
"1","(-3275,4425)","0","mstr_standard","I189";
;
CDS_LIB"mstr_standard"
BODY_TYPE"PLUMBING"
HDL_TAP"TRUE";
"B \NAC \NWC"1;
"S \NAC"
BN"27"137;
%"TAP"
"1","(-3275,4475)","0","mstr_standard","I190";
;
CDS_LIB"mstr_standard"
BODY_TYPE"PLUMBING"
HDL_TAP"TRUE";
"B \NAC \NWC"1;
"S \NAC"
BN"26"138;
%"TAP"
"1","(-3275,4325)","0","mstr_standard","I191";
;
CDS_LIB"mstr_standard"
BODY_TYPE"PLUMBING"
HDL_TAP"TRUE";
"B \NAC \NWC"1;
"S \NAC"
BN"29"133;
%"TAP"
"1","(-3275,4225)","0","mstr_standard","I192";
;
CDS_LIB"mstr_standard"
BODY_TYPE"PLUMBING"
HDL_TAP"TRUE";
"B \NAC \NWC"1;
"S \NAC"
BN"31"128;
%"TAP"
"1","(-3275,4275)","0","mstr_standard","I193";
;
CDS_LIB"mstr_standard"
BODY_TYPE"PLUMBING"
HDL_TAP"TRUE";
"B \NAC \NWC"1;
"S \NAC"
BN"30"129;
%"TAP"
"1","(-3275,4125)","0","mstr_standard","I194";
;
CDS_LIB"mstr_standard"
BODY_TYPE"PLUMBING"
HDL_TAP"TRUE";
"B \NAC \NWC"2;
"S \NAC"
BN"0"130;
%"TAP"
"1","(-3275,3975)","0","mstr_standard","I196";
;
CDS_LIB"mstr_standard"
BODY_TYPE"PLUMBING"
HDL_TAP"TRUE";
"B \NAC \NWC"2;
"S \NAC"
BN"3"107;
%"TAP"
"1","(-3275,4075)","0","mstr_standard","I197";
;
CDS_LIB"mstr_standard"
BODY_TYPE"PLUMBING"
HDL_TAP"TRUE";
"B \NAC \NWC"2;
"S \NAC"
BN"1"109;
%"TAP"
"1","(-3275,4025)","0","mstr_standard","I198";
;
CDS_LIB"mstr_standard"
BODY_TYPE"PLUMBING"
HDL_TAP"TRUE";
"B \NAC \NWC"2;
"S \NAC"
BN"2"108;
%"TAP"
"1","(-3275,3875)","0","mstr_standard","I199";
;
CDS_LIB"mstr_standard"
BODY_TYPE"PLUMBING"
HDL_TAP"TRUE";
"B \NAC \NWC"2;
"S \NAC"
BN"5"124;
%"TAP"
"1","(-3275,3925)","0","mstr_standard","I200";
;
CDS_LIB"mstr_standard"
BODY_TYPE"PLUMBING"
HDL_TAP"TRUE";
"B \NAC \NWC"2;
"S \NAC"
BN"4"125;
%"TAP"
"1","(-3275,3775)","0","mstr_standard","I201";
;
CDS_LIB"mstr_standard"
BODY_TYPE"PLUMBING"
HDL_TAP"TRUE";
"B \NAC \NWC"2;
"S \NAC"
BN"7"122;
%"TAP"
"1","(-3275,3825)","0","mstr_standard","I202";
;
CDS_LIB"mstr_standard"
BODY_TYPE"PLUMBING"
HDL_TAP"TRUE";
"B \NAC \NWC"2;
"S \NAC"
BN"6"123;
%"TAP"
"1","(-3275,3625)","0","mstr_standard","I203";
;
CDS_LIB"mstr_standard"
BODY_TYPE"PLUMBING"
HDL_TAP"TRUE";
"B \NAC \NWC"2;
"S \NAC"
BN"9"119;
%"TAP"
"1","(-3275,3675)","0","mstr_standard","I204";
;
CDS_LIB"mstr_standard"
BODY_TYPE"PLUMBING"
HDL_TAP"TRUE";
"B \NAC \NWC"2;
"S \NAC"
BN"8"121;
%"TAP"
"1","(-3275,3475)","0","mstr_standard","I205";
;
CDS_LIB"mstr_standard"
BODY_TYPE"PLUMBING"
HDL_TAP"TRUE";
"B \NAC \NWC"2;
"S \NAC"
BN"12"117;
%"TAP"
"1","(-3275,3575)","0","mstr_standard","I206";
;
CDS_LIB"mstr_standard"
BODY_TYPE"PLUMBING"
HDL_TAP"TRUE";
"B \NAC \NWC"2;
"S \NAC"
BN"10"120;
%"TAP"
"1","(-3275,3525)","0","mstr_standard","I207";
;
CDS_LIB"mstr_standard"
BODY_TYPE"PLUMBING"
HDL_TAP"TRUE";
"B \NAC \NWC"2;
"S \NAC"
BN"11"118;
%"TAP"
"1","(-3275,3375)","0","mstr_standard","I208";
;
CDS_LIB"mstr_standard"
BODY_TYPE"PLUMBING"
HDL_TAP"TRUE";
"B \NAC \NWC"2;
"S \NAC"
BN"14"115;
%"TAP"
"1","(-3275,3425)","0","mstr_standard","I209";
;
CDS_LIB"mstr_standard"
BODY_TYPE"PLUMBING"
HDL_TAP"TRUE";
"B \NAC \NWC"2;
"S \NAC"
BN"13"116;
%"TAP"
"1","(-3275,3225)","0","mstr_standard","I210";
;
CDS_LIB"mstr_standard"
BODY_TYPE"PLUMBING"
HDL_TAP"TRUE";
"B \NAC \NWC"2;
"S \NAC"
BN"16"113;
%"TAP"
"1","(-3275,3325)","0","mstr_standard","I211";
;
CDS_LIB"mstr_standard"
BODY_TYPE"PLUMBING"
HDL_TAP"TRUE";
"B \NAC \NWC"2;
"S \NAC"
BN"15"114;
%"TAP"
"1","(-3275,3175)","0","mstr_standard","I212";
;
CDS_LIB"mstr_standard"
BODY_TYPE"PLUMBING"
HDL_TAP"TRUE";
"B \NAC \NWC"2;
"S \NAC"
BN"17"112;
%"TAP"
"1","(-3275,3125)","0","mstr_standard","I213";
;
CDS_LIB"mstr_standard"
BODY_TYPE"PLUMBING"
HDL_TAP"TRUE";
"B \NAC \NWC"2;
"S \NAC"
BN"18"111;
%"TAP"
"1","(-3275,3075)","0","mstr_standard","I214";
;
CDS_LIB"mstr_standard"
BODY_TYPE"PLUMBING"
HDL_TAP"TRUE";
"B \NAC \NWC"2;
"S \NAC"
BN"19"110;
%"TAP"
"1","(-3275,2975)","0","mstr_standard","I215";
;
CDS_LIB"mstr_standard"
BODY_TYPE"PLUMBING"
HDL_TAP"TRUE";
"B \NAC \NWC"2;
"S \NAC"
BN"21"99;
%"TAP"
"1","(-3275,3025)","0","mstr_standard","I216";
;
CDS_LIB"mstr_standard"
BODY_TYPE"PLUMBING"
HDL_TAP"TRUE";
"B \NAC \NWC"2;
"S \NAC"
BN"20"100;
%"TAP"
"1","(-3275,2925)","0","mstr_standard","I217";
;
CDS_LIB"mstr_standard"
BODY_TYPE"PLUMBING"
HDL_TAP"TRUE";
"B \NAC \NWC"2;
"S \NAC"
BN"22"98;
%"TAP"
"1","(-3275,2875)","0","mstr_standard","I218";
;
CDS_LIB"mstr_standard"
BODY_TYPE"PLUMBING"
HDL_TAP"TRUE";
"B \NAC \NWC"2;
"S \NAC"
BN"23"97;
%"TAP"
"1","(-3275,2725)","0","mstr_standard","I219";
;
CDS_LIB"mstr_standard"
BODY_TYPE"PLUMBING"
HDL_TAP"TRUE";
"B \NAC \NWC"2;
"S \NAC"
BN"25"95;
%"TAP"
"1","(-3275,2775)","0","mstr_standard","I220";
;
CDS_LIB"mstr_standard"
BODY_TYPE"PLUMBING"
HDL_TAP"TRUE";
"B \NAC \NWC"2;
"S \NAC"
BN"24"96;
%"TAP"
"1","(-3275,2675)","0","mstr_standard","I221";
;
CDS_LIB"mstr_standard"
BODY_TYPE"PLUMBING"
HDL_TAP"TRUE";
"B \NAC \NWC"2;
"S \NAC"
BN"26"94;
%"TAP"
"1","(-3275,2625)","0","mstr_standard","I222";
;
CDS_LIB"mstr_standard"
BODY_TYPE"PLUMBING"
HDL_TAP"TRUE";
"B \NAC \NWC"2;
"S \NAC"
BN"27"93;
%"TAP"
"1","(-3275,2575)","0","mstr_standard","I223";
;
CDS_LIB"mstr_standard"
BODY_TYPE"PLUMBING"
HDL_TAP"TRUE";
"B \NAC \NWC"2;
"S \NAC"
BN"28"92;
%"TAP"
"1","(-3275,2475)","0","mstr_standard","I224";
;
CDS_LIB"mstr_standard"
BODY_TYPE"PLUMBING"
HDL_TAP"TRUE";
"B \NAC \NWC"2;
"S \NAC"
BN"30"103;
%"TAP"
"1","(-3275,2525)","0","mstr_standard","I225";
;
CDS_LIB"mstr_standard"
BODY_TYPE"PLUMBING"
HDL_TAP"TRUE";
"B \NAC \NWC"2;
"S \NAC"
BN"29"91;
%"TAP"
"1","(-3275,2425)","0","mstr_standard","I226";
;
CDS_LIB"mstr_standard"
BODY_TYPE"PLUMBING"
HDL_TAP"TRUE";
"B \NAC \NWC"2;
"S \NAC"
BN"31"101;
%"TAP"
"1","(-3275,2325)","0","mstr_standard","I227";
;
CDS_LIB"mstr_standard"
BODY_TYPE"PLUMBING"
HDL_TAP"TRUE";
"B \NAC \NWC"3;
"S \NAC"
BN"0"90;
%"TAP"
"1","(-3275,2275)","0","mstr_standard","I228";
;
CDS_LIB"mstr_standard"
BODY_TYPE"PLUMBING"
HDL_TAP"TRUE";
"B \NAC \NWC"3;
"S \NAC"
BN"1"89;
%"TAP"
"1","(-3275,2225)","0","mstr_standard","I229";
;
CDS_LIB"mstr_standard"
BODY_TYPE"PLUMBING"
HDL_TAP"TRUE";
"B \NAC \NWC"3;
"S \NAC"
BN"2"106;
%"TAP"
"1","(-3275,2175)","0","mstr_standard","I230";
;
CDS_LIB"mstr_standard"
BODY_TYPE"PLUMBING"
HDL_TAP"TRUE";
"B \NAC \NWC"3;
"S \NAC"
BN"3"105;
%"TAP"
"1","(-3275,2125)","0","mstr_standard","I231";
;
CDS_LIB"mstr_standard"
BODY_TYPE"PLUMBING"
HDL_TAP"TRUE";
"B \NAC \NWC"3;
"S \NAC"
BN"4"104;
%"TAP"
"1","(-3275,2075)","0","mstr_standard","I232";
;
CDS_LIB"mstr_standard"
BODY_TYPE"PLUMBING"
HDL_TAP"TRUE";
"B \NAC \NWC"3;
"S \NAC"
BN"5"102;
%"TAP"
"1","(-3275,2025)","0","mstr_standard","I234";
;
CDS_LIB"mstr_standard"
BODY_TYPE"PLUMBING"
HDL_TAP"TRUE";
"B \NAC \NWC"3;
"S \NAC"
BN"6"87;
%"TAP"
"1","(-3275,1975)","0","mstr_standard","I235";
;
CDS_LIB"mstr_standard"
BODY_TYPE"PLUMBING"
HDL_TAP"TRUE";
"B \NAC \NWC"3;
"S \NAC"
BN"7"85;
%"TAP"
"1","(-3275,1875)","0","mstr_standard","I236";
;
CDS_LIB"mstr_standard"
BODY_TYPE"PLUMBING"
HDL_TAP"TRUE";
"B \NAC \NWC"4;
"S \NAC"
BN"0"88;
%"TAP"
"1","(-3275,1825)","0","mstr_standard","I237";
;
CDS_LIB"mstr_standard"
BODY_TYPE"PLUMBING"
HDL_TAP"TRUE";
"B \NAC \NWC"4;
"S \NAC"
BN"1"86;
%"TAP"
"1","(-3275,1775)","0","mstr_standard","I238";
;
CDS_LIB"mstr_standard"
BODY_TYPE"PLUMBING"
HDL_TAP"TRUE";
"B \NAC \NWC"4;
"S \NAC"
BN"2"84;
%"TAP"
"1","(-3275,1675)","0","mstr_standard","I239";
;
CDS_LIB"mstr_standard"
BODY_TYPE"PLUMBING"
HDL_TAP"TRUE";
"B \NAC \NWC"4;
"S \NAC"
BN"4"82;
%"TAP"
"1","(-3275,1725)","0","mstr_standard","I240";
;
CDS_LIB"mstr_standard"
BODY_TYPE"PLUMBING"
HDL_TAP"TRUE";
"B \NAC \NWC"4;
"S \NAC"
BN"3"83;
%"TAP"
"1","(-3275,1575)","0","mstr_standard","I241";
;
CDS_LIB"mstr_standard"
BODY_TYPE"PLUMBING"
HDL_TAP"TRUE";
"B \NAC \NWC"4;
"S \NAC"
BN"6"80;
%"TAP"
"1","(-3275,1625)","0","mstr_standard","I242";
;
CDS_LIB"mstr_standard"
BODY_TYPE"PLUMBING"
HDL_TAP"TRUE";
"B \NAC \NWC"4;
"S \NAC"
BN"5"81;
%"TAP"
"1","(-3275,1525)","0","mstr_standard","I243";
;
CDS_LIB"mstr_standard"
BODY_TYPE"PLUMBING"
HDL_TAP"TRUE";
"B \NAC \NWC"4;
"S \NAC"
BN"7"79;
%"TAP"
"1","(-5700,5925)","2","mstr_standard","I244";
;
CDS_LIB"mstr_standard"
BODY_TYPE"PLUMBING"
HDL_TAP"TRUE";
"B \NAC \NWC"5;
"S \NAC"
BN"0"73;
%"TAP"
"1","(-5700,5825)","2","mstr_standard","I245";
;
CDS_LIB"mstr_standard"
BODY_TYPE"PLUMBING"
HDL_TAP"TRUE";
"B \NAC \NWC"5;
"S \NAC"
BN"1"71;
%"TAP"
"1","(-5700,5625)","2","mstr_standard","I246";
;
CDS_LIB"mstr_standard"
BODY_TYPE"PLUMBING"
HDL_TAP"TRUE";
"B \NAC \NWC"5;
"S \NAC"
BN"3"67;
%"TAP"
"1","(-5700,5725)","2","mstr_standard","I247";
;
CDS_LIB"mstr_standard"
BODY_TYPE"PLUMBING"
HDL_TAP"TRUE";
"B \NAC \NWC"5;
"S \NAC"
BN"2"69;
%"TAP"
"1","(-5900,5775)","2","mstr_standard","I248";
;
CDS_LIB"mstr_standard"
BODY_TYPE"PLUMBING"
HDL_TAP"TRUE";
"B \NAC \NWC"9;
"S \NAC"
BN"1"77;
%"TAP"
"1","(-5900,5875)","2","mstr_standard","I249";
;
CDS_LIB"mstr_standard"
BODY_TYPE"PLUMBING"
HDL_TAP"TRUE";
"B \NAC \NWC"9;
"S \NAC"
BN"0"78;
%"TAP"
"1","(-5900,5675)","2","mstr_standard","I250";
;
CDS_LIB"mstr_standard"
BODY_TYPE"PLUMBING"
HDL_TAP"TRUE";
"B \NAC \NWC"9;
"S \NAC"
BN"2"76;
%"TAP"
"1","(-5700,5525)","2","mstr_standard","I251";
;
CDS_LIB"mstr_standard"
BODY_TYPE"PLUMBING"
HDL_TAP"TRUE";
"B \NAC \NWC"5;
"S \NAC"
BN"4"66;
%"TAP"
"1","(-5700,5425)","2","mstr_standard","I252";
;
CDS_LIB"mstr_standard"
BODY_TYPE"PLUMBING"
HDL_TAP"TRUE";
"B \NAC \NWC"5;
"S \NAC"
BN"5"65;
%"TAP"
"1","(-5900,5575)","2","mstr_standard","I253";
;
CDS_LIB"mstr_standard"
BODY_TYPE"PLUMBING"
HDL_TAP"TRUE";
"B \NAC \NWC"9;
"S \NAC"
BN"3"75;
%"TAP"
"1","(-5900,5475)","2","mstr_standard","I254";
;
CDS_LIB"mstr_standard"
BODY_TYPE"PLUMBING"
HDL_TAP"TRUE";
"B \NAC \NWC"9;
"S \NAC"
BN"4"74;
%"TAP"
"1","(-5700,5225)","2","mstr_standard","I255";
;
CDS_LIB"mstr_standard"
BODY_TYPE"PLUMBING"
HDL_TAP"TRUE";
"B \NAC \NWC"5;
"S \NAC"
BN"7"63;
%"TAP"
"1","(-5700,5325)","2","mstr_standard","I256";
;
CDS_LIB"mstr_standard"
BODY_TYPE"PLUMBING"
HDL_TAP"TRUE";
"B \NAC \NWC"5;
"S \NAC"
BN"6"64;
%"TAP"
"1","(-5700,5125)","2","mstr_standard","I257";
;
CDS_LIB"mstr_standard"
BODY_TYPE"PLUMBING"
HDL_TAP"TRUE";
"B \NAC \NWC"5;
"S \NAC"
BN"8"62;
%"TAP"
"1","(-5900,5275)","2","mstr_standard","I258";
;
CDS_LIB"mstr_standard"
BODY_TYPE"PLUMBING"
HDL_TAP"TRUE";
"B \NAC \NWC"9;
"S \NAC"
BN"6"70;
%"TAP"
"1","(-5900,5375)","2","mstr_standard","I259";
;
CDS_LIB"mstr_standard"
BODY_TYPE"PLUMBING"
HDL_TAP"TRUE";
"B \NAC \NWC"9;
"S \NAC"
BN"5"72;
%"TAP"
"1","(-5900,5175)","2","mstr_standard","I260";
;
CDS_LIB"mstr_standard"
BODY_TYPE"PLUMBING"
HDL_TAP"TRUE";
"B \NAC \NWC"9;
"S \NAC"
BN"7"68;
%"TAP"
"1","(-5700,4875)","2","mstr_standard","I261";
;
CDS_LIB"mstr_standard"
BODY_TYPE"PLUMBING"
HDL_TAP"TRUE";
"B \NAC \NWC"6;
"S \NAC"
BN"0"51;
%"TAP"
"1","(-5700,5025)","2","mstr_standard","I262";
;
CDS_LIB"mstr_standard"
BODY_TYPE"PLUMBING"
HDL_TAP"TRUE";
"B \NAC \NWC"5;
"S \NAC"
BN"9"44;
%"TAP"
"1","(-5900,5075)","2","mstr_standard","I263";
;
CDS_LIB"mstr_standard"
BODY_TYPE"PLUMBING"
HDL_TAP"TRUE";
"B \NAC \NWC"9;
"S \NAC"
BN"8"55;
%"TAP"
"1","(-5900,4975)","2","mstr_standard","I264";
;
CDS_LIB"mstr_standard"
BODY_TYPE"PLUMBING"
HDL_TAP"TRUE";
"B \NAC \NWC"9;
"S \NAC"
BN"9"53;
%"TAP"
"1","(-5700,4775)","2","mstr_standard","I265";
;
CDS_LIB"mstr_standard"
BODY_TYPE"PLUMBING"
HDL_TAP"TRUE";
"B \NAC \NWC"6;
"S \NAC"
BN"1"49;
%"TAP"
"1","(-5700,4675)","2","mstr_standard","I266";
;
CDS_LIB"mstr_standard"
BODY_TYPE"PLUMBING"
HDL_TAP"TRUE";
"B \NAC \NWC"6;
"S \NAC"
BN"2"47;
%"TAP"
"1","(-5900,4825)","2","mstr_standard","I267";
;
CDS_LIB"mstr_standard"
BODY_TYPE"PLUMBING"
HDL_TAP"TRUE";
"B \NAC \NWC"10;
"S \NAC"
BN"0"58;
%"TAP"
"1","(-5900,4725)","2","mstr_standard","I268";
;
CDS_LIB"mstr_standard"
BODY_TYPE"PLUMBING"
HDL_TAP"TRUE";
"B \NAC \NWC"10;
"S \NAC"
BN"1"57;
%"TAP"
"1","(-5900,4625)","2","mstr_standard","I269";
;
CDS_LIB"mstr_standard"
BODY_TYPE"PLUMBING"
HDL_TAP"TRUE";
"B \NAC \NWC"10;
"S \NAC"
BN"2"56;
%"TAP"
"1","(-5700,4475)","2","mstr_standard","I270";
;
CDS_LIB"mstr_standard"
BODY_TYPE"PLUMBING"
HDL_TAP"TRUE";
"B \NAC \NWC"6;
"S \NAC"
BN"4"43;
%"TAP"
"1","(-5700,4575)","2","mstr_standard","I271";
;
CDS_LIB"mstr_standard"
BODY_TYPE"PLUMBING"
HDL_TAP"TRUE";
"B \NAC \NWC"6;
"S \NAC"
BN"3"45;
%"TAP"
"1","(-5700,4375)","2","mstr_standard","I272";
;
CDS_LIB"mstr_standard"
BODY_TYPE"PLUMBING"
HDL_TAP"TRUE";
"B \NAC \NWC"6;
"S \NAC"
BN"5"61;
%"TAP"
"1","(-5900,4525)","2","mstr_standard","I273";
;
CDS_LIB"mstr_standard"
BODY_TYPE"PLUMBING"
HDL_TAP"TRUE";
"B \NAC \NWC"10;
"S \NAC"
BN"3"54;
%"TAP"
"1","(-5900,4425)","2","mstr_standard","I274";
;
CDS_LIB"mstr_standard"
BODY_TYPE"PLUMBING"
HDL_TAP"TRUE";
"B \NAC \NWC"10;
"S \NAC"
BN"4"52;
%"TAP"
"1","(-5700,4275)","2","mstr_standard","I275";
;
CDS_LIB"mstr_standard"
BODY_TYPE"PLUMBING"
HDL_TAP"TRUE";
"B \NAC \NWC"6;
"S \NAC"
BN"6"60;
%"TAP"
"1","(-5700,4175)","2","mstr_standard","I276";
;
CDS_LIB"mstr_standard"
BODY_TYPE"PLUMBING"
HDL_TAP"TRUE";
"B \NAC \NWC"6;
"S \NAC"
BN"7"59;
%"TAP"
"1","(-5900,4225)","2","mstr_standard","I277";
;
CDS_LIB"mstr_standard"
BODY_TYPE"PLUMBING"
HDL_TAP"TRUE";
"B \NAC \NWC"10;
"S \NAC"
BN"6"48;
%"TAP"
"1","(-5900,4325)","2","mstr_standard","I278";
;
CDS_LIB"mstr_standard"
BODY_TYPE"PLUMBING"
HDL_TAP"TRUE";
"B \NAC \NWC"10;
"S \NAC"
BN"5"50;
%"TAP"
"1","(-5900,4125)","2","mstr_standard","I279";
;
CDS_LIB"mstr_standard"
BODY_TYPE"PLUMBING"
HDL_TAP"TRUE";
"B \NAC \NWC"10;
"S \NAC"
BN"7"46;
%"TAP"
"1","(-5700,4075)","2","mstr_standard","I284";
;
CDS_LIB"mstr_standard"
BODY_TYPE"PLUMBING"
HDL_TAP"TRUE";
"B \NAC \NWC"6;
"S \NAC"
BN"8"35;
%"TAP"
"1","(-5700,3975)","2","mstr_standard","I285";
;
CDS_LIB"mstr_standard"
BODY_TYPE"PLUMBING"
HDL_TAP"TRUE";
"B \NAC \NWC"6;
"S \NAC"
BN"9"32;
%"TAP"
"1","(-5900,4025)","2","mstr_standard","I286";
;
CDS_LIB"mstr_standard"
BODY_TYPE"PLUMBING"
HDL_TAP"TRUE";
"B \NAC \NWC"10;
"S \NAC"
BN"8"27;
%"TAP"
"1","(-5900,3925)","2","mstr_standard","I287";
;
CDS_LIB"mstr_standard"
BODY_TYPE"PLUMBING"
HDL_TAP"TRUE";
"B \NAC \NWC"10;
"S \NAC"
BN"9"42;
%"TAP"
"1","(-5900,3725)","2","mstr_standard","I288";
;
CDS_LIB"mstr_standard"
BODY_TYPE"PLUMBING"
HDL_TAP"TRUE";
"B \NAC \NWC"7;
"S \NAC"
BN"1"25;
%"TAP"
"1","(-5900,3775)","2","mstr_standard","I289";
;
CDS_LIB"mstr_standard"
BODY_TYPE"PLUMBING"
HDL_TAP"TRUE";
"B \NAC \NWC"7;
"S \NAC"
BN"0"28;
%"TAP"
"1","(-5900,3625)","2","mstr_standard","I290";
;
CDS_LIB"mstr_standard"
BODY_TYPE"PLUMBING"
HDL_TAP"TRUE";
"B \NAC \NWC"7;
"S \NAC"
BN"3"38;
%"TAP"
"1","(-5900,3675)","2","mstr_standard","I291";
;
CDS_LIB"mstr_standard"
BODY_TYPE"PLUMBING"
HDL_TAP"TRUE";
"B \NAC \NWC"7;
"S \NAC"
BN"2"40;
%"TAP"
"1","(-5900,3475)","2","mstr_standard","I292";
;
CDS_LIB"mstr_standard"
BODY_TYPE"PLUMBING"
HDL_TAP"TRUE";
"B \NAC \NWC"7;
"S \NAC"
BN"6"30;
%"TAP"
"1","(-5900,3525)","2","mstr_standard","I293";
;
CDS_LIB"mstr_standard"
BODY_TYPE"PLUMBING"
HDL_TAP"TRUE";
"B \NAC \NWC"7;
"S \NAC"
BN"5"33;
%"TAP"
"1","(-5900,3575)","2","mstr_standard","I294";
;
CDS_LIB"mstr_standard"
BODY_TYPE"PLUMBING"
HDL_TAP"TRUE";
"B \NAC \NWC"7;
"S \NAC"
BN"4"36;
%"TAP"
"1","(-5900,3375)","2","mstr_standard","I295";
;
CDS_LIB"mstr_standard"
BODY_TYPE"PLUMBING"
HDL_TAP"TRUE";
"B \NAC \NWC"8;
"S \NAC"
BN"0"26;
%"TAP"
"1","(-5900,3325)","2","mstr_standard","I296";
;
CDS_LIB"mstr_standard"
BODY_TYPE"PLUMBING"
HDL_TAP"TRUE";
"B \NAC \NWC"8;
"S \NAC"
BN"1"41;
%"TAP"
"1","(-5900,3225)","2","mstr_standard","I297";
;
CDS_LIB"mstr_standard"
BODY_TYPE"PLUMBING"
HDL_TAP"TRUE";
"B \NAC \NWC"8;
"S \NAC"
BN"3"37;
%"TAP"
"1","(-5900,3275)","2","mstr_standard","I298";
;
CDS_LIB"mstr_standard"
BODY_TYPE"PLUMBING"
HDL_TAP"TRUE";
"B \NAC \NWC"8;
"S \NAC"
BN"2"39;
%"TAP"
"1","(-5900,3075)","2","mstr_standard","I299";
;
CDS_LIB"mstr_standard"
BODY_TYPE"PLUMBING"
HDL_TAP"TRUE";
"B \NAC \NWC"8;
"S \NAC"
BN"6"29;
%"TAP"
"1","(-5900,3125)","2","mstr_standard","I300";
;
CDS_LIB"mstr_standard"
BODY_TYPE"PLUMBING"
HDL_TAP"TRUE";
"B \NAC \NWC"8;
"S \NAC"
BN"5"31;
%"TAP"
"1","(-5900,3175)","2","mstr_standard","I301";
;
CDS_LIB"mstr_standard"
BODY_TYPE"PLUMBING"
HDL_TAP"TRUE";
"B \NAC \NWC"8;
"S \NAC"
BN"4"34;
%"Q_RES"
"1","(-6575,2075)","0","pure_quanta","I313";
;
LOCATION"R511"
$SEC"1"
CDS_SEC"1"
TOLERANCE"1%"
VALUE"15   "
PART_NUMBER"CS01502FB11"
PACK_TYPE"0402LF"
CDS_LIB"pure_quanta"
WATTAGE"1/16W"
MATERIAL"CHIP";
"B"
$PN"2"13;
"A"
$PN"1"11;
END.
